G04*
G04 #@! TF.GenerationSoftware,Altium Limited,Altium Designer,23.0.1 (38)*
G04*
G04 Layer_Color=128*
%FSLAX25Y25*%
%MOIN*%
G70*
G04*
G04 #@! TF.SameCoordinates,C48E81DB-6E20-4E2D-80E6-7C5AFAA1A21F*
G04*
G04*
G04 #@! TF.FilePolarity,Positive*
G04*
G01*
G75*
%ADD82R,0.02520X0.02677*%
%ADD128R,0.02800X0.16500*%
%ADD129R,0.02800X0.12600*%
D82*
X273441Y-382293D02*
D03*
Y-378907D02*
D03*
X206441D02*
D03*
Y-382293D02*
D03*
X210441D02*
D03*
Y-378907D02*
D03*
X218341D02*
D03*
Y-382293D02*
D03*
X222641D02*
D03*
Y-378907D02*
D03*
X237941Y-382293D02*
D03*
Y-378907D02*
D03*
X241941Y-382293D02*
D03*
Y-378907D02*
D03*
X253441Y-382293D02*
D03*
Y-378907D02*
D03*
X256941D02*
D03*
Y-382293D02*
D03*
X269441D02*
D03*
Y-378907D02*
D03*
D128*
X281102Y-401427D02*
D03*
X159055D02*
D03*
X155118D02*
D03*
X186614D02*
D03*
X182677D02*
D03*
X241732D02*
D03*
X273228D02*
D03*
X269291D02*
D03*
X257480D02*
D03*
X237795D02*
D03*
X253543D02*
D03*
X222047D02*
D03*
X218110D02*
D03*
X210236D02*
D03*
X206299D02*
D03*
X190551D02*
D03*
X166929D02*
D03*
X170866D02*
D03*
X174803D02*
D03*
X178740D02*
D03*
X229921D02*
D03*
X214173D02*
D03*
X202362D02*
D03*
X249606D02*
D03*
X265354D02*
D03*
X245669D02*
D03*
X277165D02*
D03*
X261417D02*
D03*
X233858D02*
D03*
X225984D02*
D03*
X162992D02*
D03*
D129*
X151181Y-399477D02*
D03*
M02*
